(kicad_pcb
	(version 20241229)
	(generator "pcbnew")
	(generator_version "9.0")
	(general
		(thickness 1.62)
		(legacy_teardrops no)
	)
	(paper "A4")
	(title_block
		(title "OCuLink to 10GbE adapter")
		(date "2026-02-23")
		(rev "1.1.0")
		(company "Antmicro Ltd")
		(comment 1 "www.antmicro.com")
		(comment 9 "footprints 306-311 of 510")
	)
	(layers
		(0 "F.Cu" signal)
		(4 "In1.Cu" signal)
		(6 "In2.Cu" signal)
		(8 "In3.Cu" signal)
		(10 "In4.Cu" signal)
		(12 "In5.Cu" signal)
		(14 "In6.Cu" signal)
		(2 "B.Cu" signal)
		(9 "F.Adhes" user "F.Adhesive")
		(11 "B.Adhes" user "B.Adhesive")
		(13 "F.Paste" user)
		(15 "B.Paste" user)
		(5 "F.SilkS" user "F.Silkscreen")
		(7 "B.SilkS" user "B.Silkscreen")
		(1 "F.Mask" user)
		(3 "B.Mask" user)
		(17 "Dwgs.User" user "User.Drawings")
		(19 "Cmts.User" user "User.Comments")
		(21 "Eco1.User" user "User.Eco1")
		(23 "Eco2.User" user "User.Eco2")
		(25 "Edge.Cuts" user)
		(27 "Margin" user)
		(31 "F.CrtYd" user "F.Courtyard")
		(29 "B.CrtYd" user "B.Courtyard")
		(35 "F.Fab" user)
		(33 "B.Fab" user)
	)
	(footprint "antmicro-footprints:TP_SMD_0.75mm"
		(layer "B.Cu")
		(at 110.95 67.1 90)
		(property "Reference" "TP14"
			(at 0.298685 0.858866 180)
			(layer "B.SilkS")
			(effects
				(font
					(size 0.7 0.7)
					(thickness 0.15)
				)
				(justify right top mirror)
			)
		)
		(property "Value" "TP_0.75mm_SMD"
			(at 0 -1.2 90)
			(layer "B.Fab")
			(hide yes)
			(effects
				(font
					(size 0.7 0.7)
					(thickness 0.15)
				)
				(justify right top mirror)
			)
		)
		(property "Description" "SMT test point"
			(at 0 0 90)
			(layer "B.Fab")
			(hide yes)
			(effects
				(font
					(size 1.27 1.27)
					(thickness 0.15)
				)
				(justify mirror)
			)
		)
		(property "MPN" ""
			(at 0 0 90)
			(unlocked yes)
			(layer "B.Fab")
			(hide yes)
			(effects
				(font
					(size 1 1)
					(thickness 0.15)
				)
				(justify mirror)
			)
		)
		(property "Manufacturer" ""
			(at 0 0 90)
			(unlocked yes)
			(layer "B.Fab")
			(hide yes)
			(effects
				(font
					(size 1 1)
					(thickness 0.15)
				)
				(justify mirror)
			)
		)
		(property "Author" "Antmicro"
			(at 0 0 90)
			(unlocked yes)
			(layer "B.Fab")
			(hide yes)
			(effects
				(font
					(size 1 1)
					(thickness 0.15)
				)
				(justify mirror)
			)
		)
		(property "License" "Apache-2.0"
			(at 0 0 90)
			(unlocked yes)
			(layer "B.Fab")
			(hide yes)
			(effects
				(font
					(size 1 1)
					(thickness 0.15)
				)
				(justify mirror)
			)
		)
		(sheetname "/OCuLink/")
		(sheetfile "oculink.kicad_sch")
		(attr exclude_from_pos_files exclude_from_bom)
		(fp_circle
			(center 0 0)
			(end 0.475 0)
			(stroke
				(width 0.05)
				(type default)
			)
			(fill no)
			(layer "B.CrtYd")
		)
		(pad "1" smd circle
			(at 0 0 90)
			(size 0.75 0.75)
			(layers "B.Cu" "B.Mask")
			(net 319 "/OCuLink/~{PE_ RST}_R")
			(pinfunction "1")
			(pintype "passive")
		)
	)
	(footprint "antmicro-footprints:R_0402_1005Metric"
		(layer "B.Cu")
		(at 91.2 98.3 -90)
		(descr "Resistor SMD 0402")
		(tags "resistor SMD 0402")
		(property "Reference" "R141"
			(at -13.56 -0.482657 90)
			(layer "B.SilkS")
			(effects
				(font
					(size 0.7 0.7)
					(thickness 0.15)
				)
				(justify left bottom mirror)
			)
		)
		(property "Value" "R_100R_0402"
			(at -1.011843 -1.772046 90)
			(layer "B.Fab")
			(hide yes)
			(effects
				(font
					(size 0.7 0.7)
					(thickness 0.15)
				)
				(justify left bottom mirror)
			)
		)
		(property "Datasheet" "https://www.bourns.com/docs/product-datasheets/cr.pdf"
			(at 0 0 90)
			(layer "B.Fab")
			(hide yes)
			(effects
				(font
					(size 1.27 1.27)
					(thickness 0.15)
				)
				(justify mirror)
			)
		)
		(property "Description" "SMD Chip Resistor, 100 ohm, ± 1%, 62.5 mW, 0402 [1005 Metric], Thick Film, General Purpose"
			(at 0 0 90)
			(layer "B.Fab")
			(hide yes)
			(effects
				(font
					(size 1.27 1.27)
					(thickness 0.15)
				)
				(justify mirror)
			)
		)
		(property "MPN" "CR0402-FX-1000GLF"
			(at 0 0 270)
			(unlocked yes)
			(layer "B.Fab")
			(hide yes)
			(effects
				(font
					(size 1 1)
					(thickness 0.15)
				)
				(justify mirror)
			)
		)
		(property "Manufacturer" "Bourns"
			(at 0 0 270)
			(unlocked yes)
			(layer "B.Fab")
			(hide yes)
			(effects
				(font
					(size 1 1)
					(thickness 0.15)
				)
				(justify mirror)
			)
		)
		(property "License" "Apache-2.0"
			(at 0 0 270)
			(unlocked yes)
			(layer "B.Fab")
			(hide yes)
			(effects
				(font
					(size 1 1)
					(thickness 0.15)
				)
				(justify mirror)
			)
		)
		(property "Author" "Antmicro"
			(at 0 0 270)
			(unlocked yes)
			(layer "B.Fab")
			(hide yes)
			(effects
				(font
					(size 1 1)
					(thickness 0.15)
				)
				(justify mirror)
			)
		)
		(property "Val" "100R"
			(at 0 0 270)
			(unlocked yes)
			(layer "B.Fab")
			(hide yes)
			(effects
				(font
					(size 1 1)
					(thickness 0.15)
				)
				(justify mirror)
			)
		)
		(property "Tolerance" "1%"
			(at 0 0 270)
			(unlocked yes)
			(layer "B.Fab")
			(hide yes)
			(effects
				(font
					(size 1 1)
					(thickness 0.15)
				)
				(justify mirror)
			)
		)
		(sheetname "/X710-AT2 RSVD/")
		(sheetfile "x710-at2-rsvd.kicad_sch")
		(attr smd)
		(fp_rect
			(start -0.925 0.47)
			(end 0.925 -0.47)
			(stroke
				(width 0.05)
				(type default)
			)
			(fill no)
			(layer "B.CrtYd")
		)
		(fp_rect
			(start -0.5 0.25)
			(end 0.5 -0.25)
			(stroke
				(width 0.15)
				(type solid)
			)
			(fill no)
			(layer "B.Fab")
		)
		(pad "1" smd roundrect
			(at -0.48 0 270)
			(size 0.59 0.64)
			(layers "B.Cu" "B.Mask" "B.Paste")
			(roundrect_rratio 0.25)
			(net 28 "GND")
			(pintype "passive")
		)
		(pad "2" smd roundrect
			(at 0.48 0 270)
			(size 0.59 0.64)
			(layers "B.Cu" "B.Mask" "B.Paste")
			(roundrect_rratio 0.25)
			(net 129 "/X710-AT2 RSVD/RSVDP8_VSS")
			(pintype "passive")
		)
	)
	(footprint "antmicro-footprints:R_0402_1005Metric"
		(layer "B.Cu")
		(at 96.88 113.960001)
		(descr "Resistor SMD 0402")
		(tags "resistor SMD 0402")
		(property "Reference" "R50"
			(at -2.96 -0.380001 0)
			(layer "B.SilkS")
			(effects
				(font
					(size 0.7 0.7)
					(thickness 0.15)
				)
				(justify right top mirror)
			)
		)
		(property "Value" "R_100R_0402"
			(at -1.011843 -1.772046 0)
			(layer "B.Fab")
			(hide yes)
			(effects
				(font
					(size 0.7 0.7)
					(thickness 0.15)
				)
				(justify right top mirror)
			)
		)
		(property "Datasheet" "https://www.bourns.com/docs/product-datasheets/cr.pdf"
			(at 0 0 0)
			(layer "B.Fab")
			(hide yes)
			(effects
				(font
					(size 1.27 1.27)
					(thickness 0.15)
				)
				(justify mirror)
			)
		)
		(property "Description" "SMD Chip Resistor, 100 ohm, ± 1%, 62.5 mW, 0402 [1005 Metric], Thick Film, General Purpose"
			(at 0 0 0)
			(layer "B.Fab")
			(hide yes)
			(effects
				(font
					(size 1.27 1.27)
					(thickness 0.15)
				)
				(justify mirror)
			)
		)
		(property "MPN" "CR0402-FX-1000GLF"
			(at 0 0 0)
			(unlocked yes)
			(layer "B.Fab")
			(hide yes)
			(effects
				(font
					(size 1 1)
					(thickness 0.15)
				)
				(justify mirror)
			)
		)
		(property "Manufacturer" "Bourns"
			(at 0 0 0)
			(unlocked yes)
			(layer "B.Fab")
			(hide yes)
			(effects
				(font
					(size 1 1)
					(thickness 0.15)
				)
				(justify mirror)
			)
		)
		(property "License" "Apache-2.0"
			(at 0 0 0)
			(unlocked yes)
			(layer "B.Fab")
			(hide yes)
			(effects
				(font
					(size 1 1)
					(thickness 0.15)
				)
				(justify mirror)
			)
		)
		(property "Author" "Antmicro"
			(at 0 0 0)
			(unlocked yes)
			(layer "B.Fab")
			(hide yes)
			(effects
				(font
					(size 1 1)
					(thickness 0.15)
				)
				(justify mirror)
			)
		)
		(property "Val" "100R"
			(at 0 0 0)
			(unlocked yes)
			(layer "B.Fab")
			(hide yes)
			(effects
				(font
					(size 1 1)
					(thickness 0.15)
				)
				(justify mirror)
			)
		)
		(property "Tolerance" "1%"
			(at 0 0 0)
			(unlocked yes)
			(layer "B.Fab")
			(hide yes)
			(effects
				(font
					(size 1 1)
					(thickness 0.15)
				)
				(justify mirror)
			)
		)
		(sheetname "/X710-AT2 Misc/")
		(sheetfile "x710-at2-mics.kicad_sch")
		(attr smd)
		(fp_rect
			(start -0.925 0.47)
			(end 0.925 -0.47)
			(stroke
				(width 0.05)
				(type default)
			)
			(fill no)
			(layer "B.CrtYd")
		)
		(fp_rect
			(start -0.5 0.25)
			(end 0.5 -0.25)
			(stroke
				(width 0.15)
				(type solid)
			)
			(fill no)
			(layer "B.Fab")
		)
		(pad "1" smd roundrect
			(at -0.48 0)
			(size 0.59 0.64)
			(layers "B.Cu" "B.Mask" "B.Paste")
			(roundrect_rratio 0.25)
			(net 28 "GND")
			(pintype "passive")
		)
		(pad "2" smd roundrect
			(at 0.48 0)
			(size 0.59 0.64)
			(layers "B.Cu" "B.Mask" "B.Paste")
			(roundrect_rratio 0.25)
			(net 158 "Net-(U7-B_{2})")
			(pintype "passive")
		)
	)
	(footprint "antmicro-footprints:C_0402_1005Metric"
		(layer "B.Cu")
		(at 60.670003 88.449998)
		(descr "Capacitor SMD 0402")
		(tags "capacitor SMD 0402")
		(property "Reference" "C18"
			(at -1.070003 0.550002 0)
			(layer "B.SilkS")
			(effects
				(font
					(size 0.7 0.7)
					(thickness 0.15)
				)
				(justify right top mirror)
			)
		)
		(property "Value" "C_100n_0402"
			(at -1.022927 -2.155213 0)
			(layer "B.Fab")
			(hide yes)
			(effects
				(font
					(size 0.7 0.7)
					(thickness 0.15)
				)
				(justify right top mirror)
			)
		)
		(property "Datasheet" "https://www.murata.com/products/productdetail?partno=GRM155R61H104KE14%23"
			(at 0 0 0)
			(layer "B.Fab")
			(hide yes)
			(effects
				(font
					(size 1.27 1.27)
					(thickness 0.15)
				)
				(justify mirror)
			)
		)
		(property "Description" "SMD Multilayer Ceramic Capacitor, 0.1 µF, 50 V, 0402 [1005 Metric], ± 10%, X5R, GRM Series"
			(at 0 0 0)
			(layer "B.Fab")
			(hide yes)
			(effects
				(font
					(size 1.27 1.27)
					(thickness 0.15)
				)
				(justify mirror)
			)
		)
		(property "MPN" "GRM155R61H104KE14D"
			(at 0 0 0)
			(unlocked yes)
			(layer "B.Fab")
			(hide yes)
			(effects
				(font
					(size 1 1)
					(thickness 0.15)
				)
				(justify mirror)
			)
		)
		(property "Manufacturer" "Murata"
			(at 0 0 0)
			(unlocked yes)
			(layer "B.Fab")
			(hide yes)
			(effects
				(font
					(size 1 1)
					(thickness 0.15)
				)
				(justify mirror)
			)
		)
		(property "License" "Apache-2.0"
			(at 0 0 0)
			(unlocked yes)
			(layer "B.Fab")
			(hide yes)
			(effects
				(font
					(size 1 1)
					(thickness 0.15)
				)
				(justify mirror)
			)
		)
		(property "Author" "Antmicro"
			(at 0 0 0)
			(unlocked yes)
			(layer "B.Fab")
			(hide yes)
			(effects
				(font
					(size 1 1)
					(thickness 0.15)
				)
				(justify mirror)
			)
		)
		(property "Val" "100n"
			(at 0 0 0)
			(unlocked yes)
			(layer "B.Fab")
			(hide yes)
			(effects
				(font
					(size 1 1)
					(thickness 0.15)
				)
				(justify mirror)
			)
		)
		(property "Voltage" "50V"
			(at 0 0 0)
			(unlocked yes)
			(layer "B.Fab")
			(hide yes)
			(effects
				(font
					(size 1 1)
					(thickness 0.15)
				)
				(justify mirror)
			)
		)
		(property "Dielectric" "X5R"
			(at 0 0 0)
			(unlocked yes)
			(layer "B.Fab")
			(hide yes)
			(effects
				(font
					(size 1 1)
					(thickness 0.15)
				)
				(justify mirror)
			)
		)
		(sheetname "/Power/")
		(sheetfile "power.kicad_sch")
		(attr smd)
		(fp_rect
			(start -0.925 0.47)
			(end 0.925 -0.47)
			(stroke
				(width 0.05)
				(type default)
			)
			(fill no)
			(layer "B.CrtYd")
		)
		(fp_line
			(start -0.494 -0.248)
			(end -0.494 0.25)
			(stroke
				(width 0.15)
				(type solid)
			)
			(layer "B.Fab")
		)
		(fp_line
			(start -0.494 0.25)
			(end 0.504 0.25)
			(stroke
				(width 0.15)
				(type solid)
			)
			(layer "B.Fab")
		)
		(fp_line
			(start 0.504 -0.248)
			(end -0.494 -0.248)
			(stroke
				(width 0.15)
				(type solid)
			)
			(layer "B.Fab")
		)
		(fp_line
			(start 0.504 0.25)
			(end 0.504 -0.248)
			(stroke
				(width 0.15)
				(type solid)
			)
			(layer "B.Fab")
		)
		(pad "1" smd roundrect
			(at -0.48 0)
			(size 0.59 0.64)
			(layers "B.Cu" "B.Mask" "B.Paste")
			(roundrect_rratio 0.25)
			(net 28 "GND")
			(pintype "passive")
		)
		(pad "2" smd roundrect
			(at 0.48 0)
			(size 0.59 0.64)
			(layers "B.Cu" "B.Mask" "B.Paste")
			(roundrect_rratio 0.25)
			(net 303 "/Power/+VCCD_OUT")
			(pintype "passive")
		)
	)
	(footprint "antmicro-footprints:R_0402_1005Metric"
		(layer "B.Cu")
		(at 74 99.65)
		(descr "Resistor SMD 0402")
		(tags "resistor SMD 0402")
		(property "Reference" "R106"
			(at -0.85 0.45 0)
			(layer "B.SilkS")
			(effects
				(font
					(size 0.7 0.7)
					(thickness 0.15)
				)
				(justify left bottom mirror)
			)
		)
		(property "Value" "R_100R_0402"
			(at -1.011843 -1.772046 0)
			(layer "B.Fab")
			(hide yes)
			(effects
				(font
					(size 0.7 0.7)
					(thickness 0.15)
				)
				(justify right top mirror)
			)
		)
		(property "Datasheet" "https://www.bourns.com/docs/product-datasheets/cr.pdf"
			(at 0 0 0)
			(layer "B.Fab")
			(hide yes)
			(effects
				(font
					(size 1.27 1.27)
					(thickness 0.15)
				)
				(justify mirror)
			)
		)
		(property "Description" "SMD Chip Resistor, 100 ohm, ± 1%, 62.5 mW, 0402 [1005 Metric], Thick Film, General Purpose"
			(at 0 0 0)
			(layer "B.Fab")
			(hide yes)
			(effects
				(font
					(size 1.27 1.27)
					(thickness 0.15)
				)
				(justify mirror)
			)
		)
		(property "MPN" "CR0402-FX-1000GLF"
			(at 0 0 0)
			(unlocked yes)
			(layer "B.Fab")
			(hide yes)
			(effects
				(font
					(size 1 1)
					(thickness 0.15)
				)
				(justify mirror)
			)
		)
		(property "Manufacturer" "Bourns"
			(at 0 0 0)
			(unlocked yes)
			(layer "B.Fab")
			(hide yes)
			(effects
				(font
					(size 1 1)
					(thickness 0.15)
				)
				(justify mirror)
			)
		)
		(property "License" "Apache-2.0"
			(at 0 0 0)
			(unlocked yes)
			(layer "B.Fab")
			(hide yes)
			(effects
				(font
					(size 1 1)
					(thickness 0.15)
				)
				(justify mirror)
			)
		)
		(property "Author" "Antmicro"
			(at 0 0 0)
			(unlocked yes)
			(layer "B.Fab")
			(hide yes)
			(effects
				(font
					(size 1 1)
					(thickness 0.15)
				)
				(justify mirror)
			)
		)
		(property "Val" "100R"
			(at 0 0 0)
			(unlocked yes)
			(layer "B.Fab")
			(hide yes)
			(effects
				(font
					(size 1 1)
					(thickness 0.15)
				)
				(justify mirror)
			)
		)
		(property "Tolerance" "1%"
			(at 0 0 0)
			(unlocked yes)
			(layer "B.Fab")
			(hide yes)
			(effects
				(font
					(size 1 1)
					(thickness 0.15)
				)
				(justify mirror)
			)
		)
		(sheetname "/X710-AT2 Misc/")
		(sheetfile "x710-at2-mics.kicad_sch")
		(attr smd)
		(fp_rect
			(start -0.925 0.47)
			(end 0.925 -0.47)
			(stroke
				(width 0.05)
				(type default)
			)
			(fill no)
			(layer "B.CrtYd")
		)
		(fp_rect
			(start -0.5 0.25)
			(end 0.5 -0.25)
			(stroke
				(width 0.15)
				(type solid)
			)
			(fill no)
			(layer "B.Fab")
		)
		(pad "1" smd roundrect
			(at -0.48 0)
			(size 0.59 0.64)
			(layers "B.Cu" "B.Mask" "B.Paste")
			(roundrect_rratio 0.25)
			(net 28 "GND")
			(pintype "passive")
		)
		(pad "2" smd roundrect
			(at 0.48 0)
			(size 0.59 0.64)
			(layers "B.Cu" "B.Mask" "B.Paste")
			(roundrect_rratio 0.25)
			(net 47 "/X710-AT2 Misc/POR_BYPASS")
			(pintype "passive")
		)
	)
	(footprint "antmicro-footprints:C_0603_1608Metric_EIA"
		(layer "B.Cu")
		(at 83.3 125.8)
		(descr "Capacitor SMD 0603, IPC-7351 Density Level A")
		(tags "Capacitor 0603")
		(property "Reference" "C52"
			(at -0.95 -1.55 0)
			(layer "B.SilkS")
			(effects
				(font
					(size 0.7 0.7)
					(thickness 0.15)
				)
				(justify right top mirror)
			)
		)
		(property "Value" "C_22u_16V_0603"
			(at -1.42757 -1.770288 0)
			(layer "B.Fab")
			(hide yes)
			(effects
				(font
					(size 0.7 0.7)
					(thickness 0.15)
				)
				(justify right top mirror)
			)
		)
		(property "Datasheet" "https://product.samsungsem.com/mlcc/CL10A226MO7JZN.do"
			(at 0 0 0)
			(layer "B.Fab")
			(hide yes)
			(effects
				(font
					(size 1.27 1.27)
					(thickness 0.15)
				)
				(justify mirror)
			)
		)
		(property "Description" "SMD Multilayer Ceramic Capacitor"
			(at 0 0 0)
			(layer "B.Fab")
			(hide yes)
			(effects
				(font
					(size 1.27 1.27)
					(thickness 0.15)
				)
				(justify mirror)
			)
		)
		(property "MPN" "CL10A226MO7JZNC"
			(at 0 0 0)
			(unlocked yes)
			(layer "B.Fab")
			(hide yes)
			(effects
				(font
					(size 1 1)
					(thickness 0.15)
				)
				(justify mirror)
			)
		)
		(property "Manufacturer" "Samsung Electro-Mechanics"
			(at 0 0 0)
			(unlocked yes)
			(layer "B.Fab")
			(hide yes)
			(effects
				(font
					(size 1 1)
					(thickness 0.15)
				)
				(justify mirror)
			)
		)
		(property "License" "Apache-2.0"
			(at 0 0 0)
			(unlocked yes)
			(layer "B.Fab")
			(hide yes)
			(effects
				(font
					(size 1 1)
					(thickness 0.15)
				)
				(justify mirror)
			)
		)
		(property "Author" "Antmicro"
			(at 0 0 0)
			(unlocked yes)
			(layer "B.Fab")
			(hide yes)
			(effects
				(font
					(size 1 1)
					(thickness 0.15)
				)
				(justify mirror)
			)
		)
		(property "Val" "22u"
			(at 0 0 0)
			(unlocked yes)
			(layer "B.Fab")
			(hide yes)
			(effects
				(font
					(size 1 1)
					(thickness 0.15)
				)
				(justify mirror)
			)
		)
		(property "Voltage" "16V"
			(at 0 0 0)
			(unlocked yes)
			(layer "B.Fab")
			(hide yes)
			(effects
				(font
					(size 1 1)
					(thickness 0.15)
				)
				(justify mirror)
			)
		)
		(property "Dielectric" ""
			(at 0 0 0)
			(unlocked yes)
			(layer "B.Fab")
			(hide yes)
			(effects
				(font
					(size 1 1)
					(thickness 0.15)
				)
				(justify mirror)
			)
		)
		(sheetname "/2xRJ45/")
		(sheetfile "2xrj45.kicad_sch")
		(attr smd)
		(fp_line
			(start -0.15 -0.55)
			(end 0.15 -0.55)
			(stroke
				(width 0.15)
				(type solid)
			)
			(layer "B.SilkS")
		)
		(fp_line
			(start -0.15 0.55)
			(end 0.15 0.55)
			(stroke
				(width 0.15)
				(type solid)
			)
			(layer "B.SilkS")
		)
		(fp_rect
			(start -1.25 0.65)
			(end 1.25 -0.65)
			(stroke
				(width 0.05)
				(type solid)
			)
			(fill no)
			(layer "B.CrtYd")
		)
		(fp_rect
			(start -0.8 0.45)
			(end 0.8 -0.45)
			(stroke
				(width 0.15)
				(type solid)
			)
			(fill no)
			(layer "B.Fab")
		)
		(pad "1" smd roundrect
			(at -0.7 0)
			(size 0.8 1.1)
			(layers "B.Cu" "B.Mask" "B.Paste")
			(roundrect_rratio 0.2)
			(net 28 "GND")
			(pintype "passive")
		)
		(pad "2" smd roundrect
			(at 0.7 0)
			(size 0.8 1.1)
			(layers "B.Cu" "B.Mask" "B.Paste")
			(roundrect_rratio 0.2)
			(net 18 "+1V88")
			(pintype "passive")
		)
	)
)
